(kicad_pcb
	(version 20260206)
	(generator "pcbnew")
	(generator_version "10.0")
	(general
		(thickness 1.6)
		(legacy_teardrops no)
	)
	(paper "A4")
	(title_block
		(title "Wiwynn_Tioga_Pass_MB.brd")
		(comment 1 "Tioga Pass / footprints 1191-1197 of 4770")
	)
	(layers
		(0 "F.Cu" signal "TOP")
		(4 "In1.Cu" signal "L2GND")
		(6 "In2.Cu" signal "L3")
		(8 "In3.Cu" signal "L4GND")
		(10 "In4.Cu" signal "L5")
		(12 "In5.Cu" signal "L6GND")
		(14 "In6.Cu" signal "L7VCC")
		(16 "In7.Cu" signal "L8VCC")
		(18 "In8.Cu" signal "L9GND")
		(20 "In9.Cu" signal "L10")
		(22 "In10.Cu" signal "L11GND")
		(24 "In11.Cu" signal "L12")
		(26 "In12.Cu" signal "L13GND")
		(2 "B.Cu" signal "BOTTOM")
		(9 "F.Adhes" user "F.Adhesive")
		(11 "B.Adhes" user "B.Adhesive")
		(13 "F.Paste" user "Package Geometry/Pastemask Top")
		(15 "B.Paste" user "Package Geometry/Pastemask Bottom")
		(5 "F.SilkS" user "Ref Des/Silkscreen Top")
		(7 "B.SilkS" user "Ref Des/Silkscreen Bottom")
		(1 "F.Mask" user "Board Geometry/Soldermask Top")
		(3 "B.Mask" user "Board Geometry/Soldermask Bottom")
		(17 "Dwgs.User" user "User.Drawings")
		(19 "Cmts.User" user "User.Comments")
		(21 "Eco1.User" user "User.Eco1")
		(23 "Eco2.User" user "User.Eco2")
		(25 "Edge.Cuts" user "Board Geometry/Outline")
		(27 "Margin" user)
		(31 "F.CrtYd" user "Package Geometry/Place Bound Top")
		(29 "B.CrtYd" user "Package Geometry/Place Bound Bottom")
		(35 "F.Fab" user "Ref Des/Assembly Top")
		(33 "B.Fab" user "Ref Des/Assembly Bottom")
	)
	(footprint ""
		(layer "F.Cu")
		(at 318.2239 -127.0508 -90)
		(property "Reference" "C6B7"
			(at 3.07467 4.8006 0)
			(unlocked yes)
			(layer "F.SilkS")
			(effects
				(font
					(size 0.7874 0.5842)
					(thickness 0.1524)
				)
				(justify left)
			)
		)
		(property "Value" ""
			(at 0 0 270)
			(layer "F.Fab")
			(effects
				(font
					(size 1.27 1.27)
				)
			)
		)
		(duplicate_pad_numbers_are_jumpers no)
		(fp_line
			(start -2.2987 7.3533)
			(end -1.7272 7.3533)
			(stroke
				(width 0.1524)
				(type default)
			)
			(layer "F.SilkS")
		)
		(fp_line
			(start 1.7272 7.3533)
			(end 2.2987 7.3533)
			(stroke
				(width 0.1524)
				(type default)
			)
			(layer "F.SilkS")
		)
		(fp_line
			(start 2.2987 7.3533)
			(end 2.2987 -0.2413)
			(stroke
				(width 0.1524)
				(type default)
			)
			(layer "F.SilkS")
		)
		(fp_line
			(start -2.032 1.524)
			(end -1.7272 1.524)
			(stroke
				(width 0.1524)
				(type default)
			)
			(layer "F.SilkS")
		)
		(fp_line
			(start 2.032 1.524)
			(end 1.7272 1.524)
			(stroke
				(width 0.1524)
				(type default)
			)
			(layer "F.SilkS")
		)
		(fp_line
			(start -2.2987 -0.2413)
			(end -2.2987 7.3533)
			(stroke
				(width 0.1524)
				(type default)
			)
			(layer "F.SilkS")
		)
		(fp_line
			(start -2.032 -0.2413)
			(end -2.2987 -0.2413)
			(stroke
				(width 0.1524)
				(type default)
			)
			(layer "F.SilkS")
		)
		(fp_line
			(start 2.2987 -0.2413)
			(end 2.032 -0.2413)
			(stroke
				(width 0.1524)
				(type default)
			)
			(layer "F.SilkS")
		)
		(fp_line
			(start -2.032 -1.524)
			(end -2.032 1.524)
			(stroke
				(width 0.1524)
				(type default)
			)
			(layer "F.SilkS")
		)
		(fp_line
			(start -1.7272 -1.524)
			(end -2.032 -1.524)
			(stroke
				(width 0.1524)
				(type default)
			)
			(layer "F.SilkS")
		)
		(fp_line
			(start 1.7272 -1.524)
			(end 2.032 -1.524)
			(stroke
				(width 0.1524)
				(type default)
			)
			(layer "F.SilkS")
		)
		(fp_line
			(start 2.032 -1.524)
			(end 2.032 1.524)
			(stroke
				(width 0.1524)
				(type default)
			)
			(layer "F.SilkS")
		)
		(fp_poly
			(pts
				(xy -2.2987 -0.2413) (xy 2.2987 -0.2413) (xy 2.2987 7.3533) (xy -2.2987 7.3533)
			)
			(stroke
				(width 0)
				(type default)
			)
			(fill no)
			(layer "F.CrtYd")
		)
		(fp_line
			(start -2.2987 7.3533)
			(end -2.2987 -0.2413)
			(stroke
				(width 0.1)
				(type default)
			)
			(layer "F.Fab")
		)
		(fp_line
			(start 2.2987 7.3533)
			(end -2.2987 7.3533)
			(stroke
				(width 0.1)
				(type default)
			)
			(layer "F.Fab")
		)
		(fp_line
			(start -2.2987 -0.2413)
			(end 2.2987 -0.2413)
			(stroke
				(width 0.1)
				(type default)
			)
			(layer "F.Fab")
		)
		(fp_line
			(start 2.2987 -0.2413)
			(end 2.2987 7.3533)
			(stroke
				(width 0.1)
				(type default)
			)
			(layer "F.Fab")
		)
		(pad "1" smd rect
			(at 0 0 270)
			(size 2.54 3.048)
			(layers "F.Cu" "F.Mask" "F.Paste")
			(net "PVPP_DEF")
		)
		(pad "2" smd rect
			(at 0 7.112 270)
			(size 2.54 3.048)
			(layers "F.Cu" "F.Mask" "F.Paste")
			(net "GND")
		)
	)
	(footprint ""
		(layer "F.Cu")
		(at 28.1305 -90.551 90)
		(property "Reference" "RT9"
			(at 1.01473 0.656336 0)
			(unlocked yes)
			(layer "F.SilkS")
			(effects
				(font
					(size 0.4064 0.254)
					(thickness 0.1524)
				)
			)
		)
		(property "Value" ""
			(at 0 0 90)
			(layer "F.Fab")
			(effects
				(font
					(size 1.27 1.27)
				)
			)
		)
		(duplicate_pad_numbers_are_jumpers no)
		(fp_poly
			(pts
				(xy -0.4953 -0.2032) (xy 0.4953 -0.2032) (xy 0.4953 1.6002) (xy -0.4953 1.6002)
			)
			(stroke
				(width 0)
				(type default)
			)
			(fill no)
			(layer "F.CrtYd")
		)
		(fp_line
			(start 0.4953 -0.2032)
			(end 0.4953 1.6002)
			(stroke
				(width 0.1)
				(type default)
			)
			(layer "F.Fab")
		)
		(fp_line
			(start -0.4953 -0.2032)
			(end 0.4953 -0.2032)
			(stroke
				(width 0.1)
				(type default)
			)
			(layer "F.Fab")
		)
		(fp_line
			(start 0.4953 1.6002)
			(end -0.4953 1.6002)
			(stroke
				(width 0.1)
				(type default)
			)
			(layer "F.Fab")
		)
		(fp_line
			(start -0.4953 1.6002)
			(end -0.4953 -0.2032)
			(stroke
				(width 0.1)
				(type default)
			)
			(layer "F.Fab")
		)
		(pad "1" smd rect
			(at 0 0 90)
			(size 0.762 0.889)
			(layers "F.Cu" "F.Mask" "F.Paste")
			(net "VR_PVCCIN_CPU1_PH5_BOOT")
		)
		(pad "2" smd rect
			(at 0 1.397 90)
			(size 0.762 0.889)
			(layers "F.Cu" "F.Mask" "F.Paste")
			(net "VR_PVCCIN_CPU1_PH5_BOOT_R")
		)
		(zone
			(layer "F.Cu")
			(hatch none 0.5)
			(connect_pads
				(clearance 0)
			)
			(min_thickness 0.25)
			(keepout
				(tracks allowed)
				(vias not_allowed)
				(pads allowed)
				(copperpour not_allowed)
				(footprints allowed)
			)
			(placement
				(enabled no)
				(sheetname "")
			)
			(fill
				(thermal_gap 0.5)
				(thermal_bridge_width 0.5)
				(island_removal_mode 0)
			)
			(polygon
				(pts
					(xy 29.083 -90.932) (xy 28.575 -90.932) (xy 28.575 -90.17) (xy 29.083 -90.17)
				)
			)
		)
		(zone
			(layer "F.Cu")
			(hatch none 0.5)
			(connect_pads
				(clearance 0)
			)
			(min_thickness 0.25)
			(keepout
				(tracks not_allowed)
				(vias allowed)
				(pads allowed)
				(copperpour not_allowed)
				(footprints allowed)
			)
			(placement
				(enabled no)
				(sheetname "")
			)
			(fill
				(thermal_gap 0.5)
				(thermal_bridge_width 0.5)
				(island_removal_mode 0)
			)
			(polygon
				(pts
					(xy 29.083 -90.17) (xy 29.083 -90.932) (xy 28.575 -90.932) (xy 28.575 -90.17)
				)
			)
		)
	)
	(footprint ""
		(layer "F.Cu")
		(at 439.293 -12.954 180)
		(property "Reference" "R2U41"
			(at 0 0 180)
			(layer "F.SilkS")
			(hide yes)
			(effects
				(font
					(size 1.27 1.27)
				)
			)
		)
		(property "Value" ""
			(at 0 0 180)
			(layer "F.Fab")
			(effects
				(font
					(size 1.27 1.27)
				)
			)
		)
		(duplicate_pad_numbers_are_jumpers no)
		(fp_poly
			(pts
				(xy -0.2794 -0.1016) (xy 0.2794 -0.1016) (xy 0.2794 0.9906) (xy -0.2794 0.9906)
			)
			(stroke
				(width 0)
				(type default)
			)
			(fill no)
			(layer "F.CrtYd")
		)
		(fp_line
			(start 0.2794 0.9906)
			(end 0.2794 -0.1016)
			(stroke
				(width 0.1)
				(type default)
			)
			(layer "F.Fab")
		)
		(fp_line
			(start 0.2794 -0.1016)
			(end -0.2794 -0.1016)
			(stroke
				(width 0.1)
				(type default)
			)
			(layer "F.Fab")
		)
		(fp_line
			(start -0.2794 0.9906)
			(end 0.2794 0.9906)
			(stroke
				(width 0.1)
				(type default)
			)
			(layer "F.Fab")
		)
		(fp_line
			(start -0.2794 -0.1016)
			(end -0.2794 0.9906)
			(stroke
				(width 0.1)
				(type default)
			)
			(layer "F.Fab")
		)
		(pad "1" smd rect
			(at 0 0 180)
			(size 0.508 0.508)
			(layers "F.Cu" "F.Mask" "F.Paste")
			(net "PVCCIO_CPU0")
		)
		(pad "2" smd rect
			(at 0 0.889 180)
			(size 0.508 0.508)
			(layers "F.Cu" "F.Mask" "F.Paste")
			(net "H_CPU0_MEMDEF_MEMHOT_G_N")
		)
		(zone
			(layer "F.Cu")
			(hatch none 0.5)
			(connect_pads
				(clearance 0)
			)
			(min_thickness 0.25)
			(keepout
				(tracks not_allowed)
				(vias allowed)
				(pads allowed)
				(copperpour not_allowed)
				(footprints allowed)
			)
			(placement
				(enabled no)
				(sheetname "")
			)
			(fill
				(thermal_gap 0.5)
				(thermal_bridge_width 0.5)
				(island_removal_mode 0)
			)
			(polygon
				(pts
					(xy 439.547 -13.589) (xy 439.039 -13.589) (xy 439.039 -13.208) (xy 439.547 -13.208)
				)
			)
		)
		(zone
			(layer "F.Cu")
			(hatch none 0.5)
			(connect_pads
				(clearance 0)
			)
			(min_thickness 0.25)
			(keepout
				(tracks allowed)
				(vias not_allowed)
				(pads allowed)
				(copperpour not_allowed)
				(footprints allowed)
			)
			(placement
				(enabled no)
				(sheetname "")
			)
			(fill
				(thermal_gap 0.5)
				(thermal_bridge_width 0.5)
				(island_removal_mode 0)
			)
			(polygon
				(pts
					(xy 439.547 -13.208) (xy 439.039 -13.208) (xy 439.039 -13.589) (xy 439.547 -13.589)
				)
			)
		)
	)
	(footprint ""
		(layer "F.Cu")
		(at 410.6926 -103.3526)
		(property "Reference" "R7W11"
			(at -0.8382 -0.67818 0)
			(unlocked yes)
			(layer "F.SilkS")
			(effects
				(font
					(size 0.4064 0.254)
					(thickness 0.1524)
				)
				(justify left)
			)
		)
		(property "Value" ""
			(at 0 0 0)
			(layer "F.Fab")
			(effects
				(font
					(size 1.27 1.27)
				)
			)
		)
		(duplicate_pad_numbers_are_jumpers no)
		(fp_poly
			(pts
				(xy -0.2794 -0.1016) (xy 0.2794 -0.1016) (xy 0.2794 0.9906) (xy -0.2794 0.9906)
			)
			(stroke
				(width 0)
				(type default)
			)
			(fill no)
			(layer "F.CrtYd")
		)
		(fp_line
			(start -0.2794 -0.1016)
			(end -0.2794 0.9906)
			(stroke
				(width 0.1)
				(type default)
			)
			(layer "F.Fab")
		)
		(fp_line
			(start -0.2794 0.9906)
			(end 0.2794 0.9906)
			(stroke
				(width 0.1)
				(type default)
			)
			(layer "F.Fab")
		)
		(fp_line
			(start 0.2794 -0.1016)
			(end -0.2794 -0.1016)
			(stroke
				(width 0.1)
				(type default)
			)
			(layer "F.Fab")
		)
		(fp_line
			(start 0.2794 0.9906)
			(end 0.2794 -0.1016)
			(stroke
				(width 0.1)
				(type default)
			)
			(layer "F.Fab")
		)
		(pad "1" smd rect
			(at 0 0)
			(size 0.508 0.508)
			(layers "F.Cu" "F.Mask" "F.Paste")
			(net "FM_CPU1_RC_ERROR_R_N")
		)
		(pad "2" smd rect
			(at 0 0.889)
			(size 0.508 0.508)
			(layers "F.Cu" "F.Mask" "F.Paste")
			(net "FM_CPU1_RC_ERROR_N")
		)
		(zone
			(layer "F.Cu")
			(hatch none 0.5)
			(connect_pads
				(clearance 0)
			)
			(min_thickness 0.25)
			(keepout
				(tracks allowed)
				(vias not_allowed)
				(pads allowed)
				(copperpour not_allowed)
				(footprints allowed)
			)
			(placement
				(enabled no)
				(sheetname "")
			)
			(fill
				(thermal_gap 0.5)
				(thermal_bridge_width 0.5)
				(island_removal_mode 0)
			)
			(polygon
				(pts
					(xy 410.4386 -103.0986) (xy 410.9466 -103.0986) (xy 410.9466 -102.7176) (xy 410.4386 -102.7176)
				)
			)
		)
		(zone
			(layer "F.Cu")
			(hatch none 0.5)
			(connect_pads
				(clearance 0)
			)
			(min_thickness 0.25)
			(keepout
				(tracks not_allowed)
				(vias allowed)
				(pads allowed)
				(copperpour not_allowed)
				(footprints allowed)
			)
			(placement
				(enabled no)
				(sheetname "")
			)
			(fill
				(thermal_gap 0.5)
				(thermal_bridge_width 0.5)
				(island_removal_mode 0)
			)
			(polygon
				(pts
					(xy 410.4386 -102.7176) (xy 410.9466 -102.7176) (xy 410.9466 -103.0986) (xy 410.4386 -103.0986)
				)
			)
		)
	)
	(footprint ""
		(layer "F.Cu")
		(at 479.9076 -22.4282)
		(property "Reference" "C8E10"
			(at -0.381 -1.21793 0)
			(unlocked yes)
			(layer "F.SilkS")
			(effects
				(font
					(size 0.7874 0.5842)
					(thickness 0.1524)
				)
			)
		)
		(property "Value" ""
			(at 0 0 0)
			(layer "F.Fab")
			(effects
				(font
					(size 1.27 1.27)
				)
			)
		)
		(duplicate_pad_numbers_are_jumpers no)
		(fp_line
			(start -0.9017 1.953006)
			(end -0.9017 0.823976)
			(stroke
				(width 0.1524)
				(type default)
			)
			(layer "F.SilkS")
		)
		(fp_line
			(start 0.9017 1.953768)
			(end 0.9017 0.824484)
			(stroke
				(width 0.1524)
				(type default)
			)
			(layer "F.SilkS")
		)
		(fp_poly
			(pts
				(xy -0.9017 -0.3048) (xy 0.9017 -0.3048) (xy 0.9017 3.0988) (xy -0.9017 3.0988)
			)
			(stroke
				(width 0)
				(type default)
			)
			(fill no)
			(layer "F.CrtYd")
		)
		(fp_line
			(start -0.9017 -0.3048)
			(end -0.9017 3.0988)
			(stroke
				(width 0.1)
				(type default)
			)
			(layer "F.Fab")
		)
		(fp_line
			(start -0.9017 3.0988)
			(end 0.9017 3.0988)
			(stroke
				(width 0.1)
				(type default)
			)
			(layer "F.Fab")
		)
		(fp_line
			(start 0.9017 -0.3048)
			(end -0.9017 -0.3048)
			(stroke
				(width 0.1)
				(type default)
			)
			(layer "F.Fab")
		)
		(fp_line
			(start 0.9017 3.0988)
			(end 0.9017 -0.3048)
			(stroke
				(width 0.1)
				(type default)
			)
			(layer "F.Fab")
		)
		(pad "1" smd rect
			(at 0 0)
			(size 1.524 1.016)
			(layers "F.Cu" "F.Mask" "F.Paste")
			(net "VR_FET_SW_P12V_STBY_P3V3_STBY")
		)
		(pad "2" smd rect
			(at 0 2.794)
			(size 1.524 1.016)
			(layers "F.Cu" "F.Mask" "F.Paste")
			(net "GND")
		)
		(zone
			(layer "F.Cu")
			(hatch none 0.5)
			(connect_pads
				(clearance 0)
			)
			(min_thickness 0.25)
			(keepout
				(tracks allowed)
				(vias not_allowed)
				(pads allowed)
				(copperpour not_allowed)
				(footprints allowed)
			)
			(placement
				(enabled no)
				(sheetname "")
			)
			(fill
				(thermal_gap 0.5)
				(thermal_bridge_width 0.5)
				(island_removal_mode 0)
			)
			(polygon
				(pts
					(xy 480.6696 -21.9202) (xy 480.6696 -20.1422) (xy 479.1456 -20.1422) (xy 479.1456 -21.9202)
				)
			)
		)
	)
	(footprint ""
		(layer "F.Cu")
		(at 433.07 -15.113)
		(property "Reference" "R6W45"
			(at -0.8382 -0.67818 0)
			(unlocked yes)
			(layer "F.SilkS")
			(effects
				(font
					(size 0.4064 0.254)
					(thickness 0.1524)
				)
				(justify left)
			)
		)
		(property "Value" ""
			(at 0 0 0)
			(layer "F.Fab")
			(effects
				(font
					(size 1.27 1.27)
				)
			)
		)
		(duplicate_pad_numbers_are_jumpers no)
		(fp_poly
			(pts
				(xy -0.2794 -0.1016) (xy 0.2794 -0.1016) (xy 0.2794 0.9906) (xy -0.2794 0.9906)
			)
			(stroke
				(width 0)
				(type default)
			)
			(fill no)
			(layer "F.CrtYd")
		)
		(fp_line
			(start -0.2794 -0.1016)
			(end -0.2794 0.9906)
			(stroke
				(width 0.1)
				(type default)
			)
			(layer "F.Fab")
		)
		(fp_line
			(start -0.2794 0.9906)
			(end 0.2794 0.9906)
			(stroke
				(width 0.1)
				(type default)
			)
			(layer "F.Fab")
		)
		(fp_line
			(start 0.2794 -0.1016)
			(end -0.2794 -0.1016)
			(stroke
				(width 0.1)
				(type default)
			)
			(layer "F.Fab")
		)
		(fp_line
			(start 0.2794 0.9906)
			(end 0.2794 -0.1016)
			(stroke
				(width 0.1)
				(type default)
			)
			(layer "F.Fab")
		)
		(pad "1" smd rect
			(at 0 0)
			(size 0.508 0.508)
			(layers "F.Cu" "F.Mask" "F.Paste")
			(net "PCA9554_A2")
		)
		(pad "2" smd rect
			(at 0 0.889)
			(size 0.508 0.508)
			(layers "F.Cu" "F.Mask" "F.Paste")
			(net "GND")
		)
		(zone
			(layer "F.Cu")
			(hatch none 0.5)
			(connect_pads
				(clearance 0)
			)
			(min_thickness 0.25)
			(keepout
				(tracks allowed)
				(vias not_allowed)
				(pads allowed)
				(copperpour not_allowed)
				(footprints allowed)
			)
			(placement
				(enabled no)
				(sheetname "")
			)
			(fill
				(thermal_gap 0.5)
				(thermal_bridge_width 0.5)
				(island_removal_mode 0)
			)
			(polygon
				(pts
					(xy 432.816 -14.859) (xy 433.324 -14.859) (xy 433.324 -14.478) (xy 432.816 -14.478)
				)
			)
		)
		(zone
			(layer "F.Cu")
			(hatch none 0.5)
			(connect_pads
				(clearance 0)
			)
			(min_thickness 0.25)
			(keepout
				(tracks not_allowed)
				(vias allowed)
				(pads allowed)
				(copperpour not_allowed)
				(footprints allowed)
			)
			(placement
				(enabled no)
				(sheetname "")
			)
			(fill
				(thermal_gap 0.5)
				(thermal_bridge_width 0.5)
				(island_removal_mode 0)
			)
			(polygon
				(pts
					(xy 432.816 -14.478) (xy 433.324 -14.478) (xy 433.324 -14.859) (xy 432.816 -14.859)
				)
			)
		)
	)
	(footprint ""
		(layer "F.Cu")
		(at 386.842 -87.3125 180)
		(property "Reference" "R7C14"
			(at 0 0 180)
			(layer "F.SilkS")
			(hide yes)
			(effects
				(font
					(size 1.27 1.27)
				)
			)
		)
		(property "Value" ""
			(at 0 0 180)
			(layer "F.Fab")
			(effects
				(font
					(size 1.27 1.27)
				)
			)
		)
		(duplicate_pad_numbers_are_jumpers no)
		(fp_poly
			(pts
				(xy -0.2794 -0.1016) (xy 0.2794 -0.1016) (xy 0.2794 0.9906) (xy -0.2794 0.9906)
			)
			(stroke
				(width 0)
				(type default)
			)
			(fill no)
			(layer "F.CrtYd")
		)
		(fp_line
			(start 0.2794 0.9906)
			(end 0.2794 -0.1016)
			(stroke
				(width 0.1)
				(type default)
			)
			(layer "F.Fab")
		)
		(fp_line
			(start 0.2794 -0.1016)
			(end -0.2794 -0.1016)
			(stroke
				(width 0.1)
				(type default)
			)
			(layer "F.Fab")
		)
		(fp_line
			(start -0.2794 0.9906)
			(end 0.2794 0.9906)
			(stroke
				(width 0.1)
				(type default)
			)
			(layer "F.Fab")
		)
		(fp_line
			(start -0.2794 -0.1016)
			(end -0.2794 0.9906)
			(stroke
				(width 0.1)
				(type default)
			)
			(layer "F.Fab")
		)
		(pad "1" smd rect
			(at 0 0 180)
			(size 0.508 0.508)
			(layers "F.Cu" "F.Mask" "F.Paste")
			(net "RMII_BMC_PCH_SPRNGVLLE_RXER")
		)
		(pad "2" smd rect
			(at 0 0.889 180)
			(size 0.508 0.508)
			(layers "F.Cu" "F.Mask" "F.Paste")
			(net "RMII_BMC_PCH_SPRNGVLLE_RXER_R")
		)
		(zone
			(layer "F.Cu")
			(hatch none 0.5)
			(connect_pads
				(clearance 0)
			)
			(min_thickness 0.25)
			(keepout
				(tracks not_allowed)
				(vias allowed)
				(pads allowed)
				(copperpour not_allowed)
				(footprints allowed)
			)
			(placement
				(enabled no)
				(sheetname "")
			)
			(fill
				(thermal_gap 0.5)
				(thermal_bridge_width 0.5)
				(island_removal_mode 0)
			)
			(polygon
				(pts
					(xy 387.096 -87.9475) (xy 386.588 -87.9475) (xy 386.588 -87.5665) (xy 387.096 -87.5665)
				)
			)
		)
		(zone
			(layer "F.Cu")
			(hatch none 0.5)
			(connect_pads
				(clearance 0)
			)
			(min_thickness 0.25)
			(keepout
				(tracks allowed)
				(vias not_allowed)
				(pads allowed)
				(copperpour not_allowed)
				(footprints allowed)
			)
			(placement
				(enabled no)
				(sheetname "")
			)
			(fill
				(thermal_gap 0.5)
				(thermal_bridge_width 0.5)
				(island_removal_mode 0)
			)
			(polygon
				(pts
					(xy 387.096 -87.5665) (xy 386.588 -87.5665) (xy 386.588 -87.9475) (xy 387.096 -87.9475)
				)
			)
		)
	)
)
